FILE_TYPE = MACRO_DRAWING;
SET COLOR_WIRE YELLOW;
SET COLOR_PROP ORANGE;
SET COLOR_DOT WHITE;
SET COLOR_ARC YELLOW;
SET COLOR_BODY GREEN;
SET COLOR_NOTE PURPLE;
SET PROP_DISPLAY VALUE;
SET PAGE_NUMBER P526;
FORCEADD SHEET_A1..1
(800 800);
FORCEPROP 2 LAST CUSTOM_TXT_CDS <XR_PAGE_TITLE>
J 0
(-14770 12150);
DISPLAY 0.638298 (-14770 12150);
PAINT PINK (-14770 12150);
FORCEPROP 1 LAST CUSTOM_TXT_CDS <DOCNO>
J 0
(-1250 1185);
DISPLAY 0.978723 (-1250 1185);
FORCEPROP 1 LAST CUSTOM_TXT_CDS <CON_PAGE_NUM>
J 0
(-1355 850);
DISPLAY 0.978723 (-1355 850);
FORCEPROP 1 LAST CUSTOM_TXT_CDS <DATE>
J 0
(100 975);
DISPLAY 0.978723 (100 975);
FORCEPROP 1 LAST CUSTOM_TXT_CDS <TITLE>
J 1
(-985 1430);
DISPLAY 0.978723 (-985 1430);
FORCEPROP 1 LAST CUSTOM_TXT_CDS <DESIGNER>
J 0
(100 1400);
DISPLAY 0.978723 (100 1400);
FORCEPROP 1 LAST CUSTOM_TXT_CDS <CON_TOTAL_PAGES>
J 0
(-1045 850);
DISPLAY 0.808511 (-1045 850);
FORCEPROP 1 LAST CUSTOM_TXT_CDS <ASSY_PN>
J 0
(-1250 975);
DISPLAY 0.978723 (-1250 975);
FORCEPROP 1 LAST CUSTOM_TXT_CDS <DOCREV>
J 0
(100 1175);
DISPLAY 0.978723 (100 1175);
FORCEPROP 1 LAST TITLE I2C_BLOCK_DIAGRAM
J 0
(800 800);
PAINT MONO (800 800);
DISPLAY INVISIBLE (800 800);
FORCEPROP 2 LAST CDS_LIB cls
J 0
(800 800);
DISPLAY INVISIBLE (800 800);
FORCEPROP 1 LAST CDS_LMAN_SYM_OUTLINE -15850,11500,200,-200
J 0
(800 800);
DISPLAY 0.468085 (800 800);
PAINT GREEN (800 800);
DISPLAY INVISIBLE (800 800);
FORCEPROP 2 LAST PAGE_BORDER TRUE
J 0
(-14770 12150);
DISPLAY 0.638298 (-14770 12150);
PAINT PINK (-14770 12150);
DISPLAY INVISIBLE (-14770 12150);
FORCEPROP 1 LAST COMMENT_BODY TRUE
J 0
(810 855);
DISPLAY 0.808511 (810 855);
DISPLAY INVISIBLE (810 855);
FORCEPROP 2 LAST CDS_XR_PAGE_TITLE CR-4 : @TIMECARD_LIB.TIMECARD(SCH_1):PAGE4
J 0
(-14770 12150);
DISPLAY 0.638298 (-14770 12150);
PAINT PINK (-14770 12150);
DISPLAY INVISIBLE (-14770 12150);
FORCENOTE
I2C_BLOCK_DIAGRAM
(-9000 10850) 0;
DISPLAY LEFT (-9000 10850);
DISPLAY 4.914894 (-9000 10850);
FORCENOTE
$CDS_IMAGE|clipboard_0_7.jpg|9818|3326
(-6850 7750) 0;
DISPLAY LEFT (-6850 7750);
QUIT
